# BASEBOARD_FAB2 (Tioga Pass) — schematic netlist excerpt (pin names and nets, part order shuffled) for the footprints in the layout excerpt that follows; sources: Cadence DE-HDL packaged netlist, KiCad conversion of Wiwynn_Tioga_Pass_MB.brd

R6U6  RES  0.0 5% CHIP  pkg 0402  page 229 : A = PVDDQ_GHJ ; B = VSENSE_PVDDQ_GHJ_VTT
C5P31  CAP  100UF 4V 20% X5R  pkg 0805  page 42 : A = PVCCMCP_CPU0 ; B = GND
R6T2  RES  240 1.0% CHIP  pkg 0402  page 99 : A = PVCCIO_CPU1 ; B = SMB_DDR_GHJ_SCL_G

(kicad_pcb
	(version 20260206)
	(generator "pcbnew")
	(generator_version "10.0")
	(general
		(thickness 1.6)
		(legacy_teardrops no)
	)
	(paper "A4")
	(title_block
		(title "Wiwynn_Tioga_Pass_MB.brd")
		(comment 1 "Tioga Pass / footprints 4693-4695 of 4770")
	)
	(layers
		(0 "F.Cu" signal "TOP")
		(4 "In1.Cu" signal "L2GND")
		(6 "In2.Cu" signal "L3")
		(8 "In3.Cu" signal "L4GND")
		(10 "In4.Cu" signal "L5")
		(12 "In5.Cu" signal "L6GND")
		(14 "In6.Cu" signal "L7VCC")
		(16 "In7.Cu" signal "L8VCC")
		(18 "In8.Cu" signal "L9GND")
		(20 "In9.Cu" signal "L10")
		(22 "In10.Cu" signal "L11GND")
		(24 "In11.Cu" signal "L12")
		(26 "In12.Cu" signal "L13GND")
		(2 "B.Cu" signal "BOTTOM")
		(9 "F.Adhes" user "F.Adhesive")
		(11 "B.Adhes" user "B.Adhesive")
		(13 "F.Paste" user "Package Geometry/Pastemask Top")
		(15 "B.Paste" user "Package Geometry/Pastemask Bottom")
		(5 "F.SilkS" user "Ref Des/Silkscreen Top")
		(7 "B.SilkS" user "Ref Des/Silkscreen Bottom")
		(1 "F.Mask" user "Board Geometry/Soldermask Top")
		(3 "B.Mask" user "Board Geometry/Soldermask Bottom")
		(17 "Dwgs.User" user "User.Drawings")
		(19 "Cmts.User" user "User.Comments")
		(21 "Eco1.User" user "User.Eco1")
		(23 "Eco2.User" user "User.Eco2")
		(25 "Edge.Cuts" user "Board Geometry/Outline")
		(27 "Margin" user)
		(31 "F.CrtYd" user "Package Geometry/Place Bound Top")
		(29 "B.CrtYd" user "Package Geometry/Place Bound Bottom")
		(35 "F.Fab" user "Ref Des/Assembly Top")
		(33 "B.Fab" user "Ref Des/Assembly Bottom")
	)
	(footprint ""
		(layer "B.Cu")
		(at 167.616124 -23.562564 -90)
		(property "Reference" "R6T2"
			(at 0 0 90)
			(layer "B.SilkS")
			(hide yes)
			(effects
				(font
					(size 1.27 1.27)
				)
				(justify mirror)
			)
		)
		(property "Value" ""
			(at 0 0 90)
			(layer "B.Fab")
			(effects
				(font
					(size 1.27 1.27)
				)
				(justify mirror)
			)
		)
		(duplicate_pad_numbers_are_jumpers no)
		(fp_poly
			(pts
				(xy 0.2794 -0.1016) (xy -0.2794 -0.1016) (xy -0.2794 0.9906) (xy 0.2794 0.9906)
			)
			(stroke
				(width 0)
				(type default)
			)
			(fill no)
			(layer "B.CrtYd")
		)
		(fp_line
			(start -0.2794 0.9906)
			(end -0.2794 -0.1016)
			(stroke
				(width 0.1)
				(type default)
			)
			(layer "B.Fab")
		)
		(fp_line
			(start 0.2794 0.9906)
			(end -0.2794 0.9906)
			(stroke
				(width 0.1)
				(type default)
			)
			(layer "B.Fab")
		)
		(fp_line
			(start -0.2794 -0.1016)
			(end 0.2794 -0.1016)
			(stroke
				(width 0.1)
				(type default)
			)
			(layer "B.Fab")
		)
		(fp_line
			(start 0.2794 -0.1016)
			(end 0.2794 0.9906)
			(stroke
				(width 0.1)
				(type default)
			)
			(layer "B.Fab")
		)
		(pad "1" smd rect
			(at 0 0 90)
			(size 0.508 0.508)
			(layers "B.Cu" "B.Mask" "B.Paste")
			(net "PVCCIO_CPU1")
		)
		(pad "2" smd rect
			(at 0 0.889 90)
			(size 0.508 0.508)
			(layers "B.Cu" "B.Mask" "B.Paste")
			(net "SMB_DDR_GHJ_SCL_G")
		)
		(zone
			(layer "B.Cu")
			(hatch none 0.5)
			(connect_pads
				(clearance 0)
			)
			(min_thickness 0.25)
			(keepout
				(tracks not_allowed)
				(vias allowed)
				(pads allowed)
				(copperpour not_allowed)
				(footprints allowed)
			)
			(placement
				(enabled no)
				(sheetname "")
			)
			(fill
				(thermal_gap 0.5)
				(thermal_bridge_width 0.5)
				(island_removal_mode 0)
			)
			(polygon
				(pts
					(xy 166.981124 -23.308564) (xy 166.981124 -23.816564) (xy 167.362124 -23.816564) (xy 167.362124 -23.308564)
				)
			)
		)
		(zone
			(layer "B.Cu")
			(hatch none 0.5)
			(connect_pads
				(clearance 0)
			)
			(min_thickness 0.25)
			(keepout
				(tracks allowed)
				(vias not_allowed)
				(pads allowed)
				(copperpour not_allowed)
				(footprints allowed)
			)
			(placement
				(enabled no)
				(sheetname "")
			)
			(fill
				(thermal_gap 0.5)
				(thermal_bridge_width 0.5)
				(island_removal_mode 0)
			)
			(polygon
				(pts
					(xy 167.362124 -23.308564) (xy 167.362124 -23.816564) (xy 166.981124 -23.816564) (xy 166.981124 -23.308564)
				)
			)
		)
	)
	(footprint ""
		(layer "B.Cu")
		(at 174.809404 -4.57581 -90)
		(property "Reference" "R6U6"
			(at 0 0 90)
			(layer "B.SilkS")
			(hide yes)
			(effects
				(font
					(size 1.27 1.27)
				)
				(justify mirror)
			)
		)
		(property "Value" ""
			(at 0 0 90)
			(layer "B.Fab")
			(effects
				(font
					(size 1.27 1.27)
				)
				(justify mirror)
			)
		)
		(duplicate_pad_numbers_are_jumpers no)
		(fp_rect
			(start 0.2794 0.9906)
			(end -0.2794 -0.1016)
			(stroke
				(width 0)
				(type default)
			)
			(fill no)
			(layer "B.CrtYd")
		)
		(fp_line
			(start -0.2794 0.9906)
			(end -0.2794 -0.1016)
			(stroke
				(width 0.1)
				(type default)
			)
			(layer "B.Fab")
		)
		(fp_line
			(start 0.2794 0.9906)
			(end -0.2794 0.9906)
			(stroke
				(width 0.1)
				(type default)
			)
			(layer "B.Fab")
		)
		(fp_line
			(start -0.2794 -0.1016)
			(end 0.2794 -0.1016)
			(stroke
				(width 0.1)
				(type default)
			)
			(layer "B.Fab")
		)
		(fp_line
			(start 0.2794 -0.1016)
			(end 0.2794 0.9906)
			(stroke
				(width 0.1)
				(type default)
			)
			(layer "B.Fab")
		)
		(pad "1" smd rect
			(at 0 0 90)
			(size 0.508 0.508)
			(layers "B.Cu" "B.Mask" "B.Paste")
			(net "PVDDQ_GHJ")
		)
		(pad "2" smd rect
			(at 0 0.889 90)
			(size 0.508 0.508)
			(layers "B.Cu" "B.Mask" "B.Paste")
			(net "VSENSE_PVDDQ_GHJ_VTT")
		)
		(zone
			(layer "B.Cu")
			(hatch none 0.5)
			(connect_pads
				(clearance 0)
			)
			(min_thickness 0.25)
			(keepout
				(tracks allowed)
				(vias not_allowed)
				(pads allowed)
				(copperpour not_allowed)
				(footprints allowed)
			)
			(placement
				(enabled no)
				(sheetname "")
			)
			(fill
				(thermal_gap 0.5)
				(thermal_bridge_width 0.5)
				(island_removal_mode 0)
			)
			(polygon
				(pts
					(xy 174.174404 -4.32181) (xy 174.555404 -4.32181) (xy 174.555404 -4.82981) (xy 174.174404 -4.82981)
				)
			)
		)
		(zone
			(layer "B.Cu")
			(hatch none 0.5)
			(connect_pads
				(clearance 0)
			)
			(min_thickness 0.25)
			(keepout
				(tracks not_allowed)
				(vias allowed)
				(pads allowed)
				(copperpour not_allowed)
				(footprints allowed)
			)
			(placement
				(enabled no)
				(sheetname "")
			)
			(fill
				(thermal_gap 0.5)
				(thermal_bridge_width 0.5)
				(island_removal_mode 0)
			)
			(polygon
				(pts
					(xy 174.174404 -4.32181) (xy 174.555404 -4.32181) (xy 174.555404 -4.82981) (xy 174.174404 -4.82981)
				)
			)
		)
	)
	(footprint ""
		(layer "B.Cu")
		(at 269.521686 -73.51014)
		(property "Reference" "C5P31"
			(at 0 0 0)
			(layer "B.SilkS")
			(hide yes)
			(effects
				(font
					(size 1.27 1.27)
				)
				(justify mirror)
			)
		)
		(property "Value" ""
			(at 0 0 0)
			(layer "B.Fab")
			(effects
				(font
					(size 1.27 1.27)
				)
				(justify mirror)
			)
		)
		(duplicate_pad_numbers_are_jumpers no)
		(fp_poly
			(pts
				(xy 0.7239 -0.2159) (xy -0.7239 -0.2159) (xy -0.7239 1.9939) (xy 0.7239 1.9939)
			)
			(stroke
				(width 0)
				(type default)
			)
			(fill no)
			(layer "B.CrtYd")
		)
		(fp_line
			(start -0.7239 -0.2159)
			(end 0.7239 -0.2159)
			(stroke
				(width 0.1)
				(type default)
			)
			(layer "B.Fab")
		)
		(fp_line
			(start -0.7239 1.9939)
			(end -0.7239 -0.2159)
			(stroke
				(width 0.1)
				(type default)
			)
			(layer "B.Fab")
		)
		(fp_line
			(start 0.7239 -0.2159)
			(end 0.7239 1.9939)
			(stroke
				(width 0.1)
				(type default)
			)
			(layer "B.Fab")
		)
		(fp_line
			(start 0.7239 1.9939)
			(end -0.7239 1.9939)
			(stroke
				(width 0.1)
				(type default)
			)
			(layer "B.Fab")
		)
		(pad "1" smd rect
			(at 0 0 180)
			(size 1.27 1.016)
			(layers "B.Cu" "B.Mask" "B.Paste")
			(net "PVCCMCP_CPU0")
		)
		(pad "2" smd rect
			(at 0 1.778 180)
			(size 1.27 1.016)
			(layers "B.Cu" "B.Mask" "B.Paste")
			(net "GND")
		)
		(zone
			(layer "B.Cu")
			(hatch none 0.5)
			(connect_pads
				(clearance 0)
			)
			(min_thickness 0.25)
			(keepout
				(tracks not_allowed)
				(vias allowed)
				(pads allowed)
				(copperpour not_allowed)
				(footprints allowed)
			)
			(placement
				(enabled no)
				(sheetname "")
			)
			(fill
				(thermal_gap 0.5)
				(thermal_bridge_width 0.5)
				(island_removal_mode 0)
			)
			(polygon
				(pts
					(xy 270.156686 -73.00214) (xy 268.886686 -73.00214) (xy 268.886686 -72.24014) (xy 270.156686 -72.24014)
				)
			)
		)
	)
)
